# BASEBOARD_FAB2 (Tioga Pass) — schematic netlist excerpt (pin names and nets, part order shuffled) for the footprints in the layout excerpt that follows; sources: Cadence DE-HDL packaged netlist, KiCad conversion of Wiwynn_Tioga_Pass_MB.brd

C1F3  CAP  0.22UF 16V 10% X7R  pkg 0402  page 181 : A = P3E_CPU1_PE3_MP_C_TXN<7> ; B = P3E_CPU1_PE3_MP_TXN<7>
RF7  RES  1.0K 0.1% CHIP  pkg 0402  page 206 : A = VR_PVCCIN_CPU1_AIREF1 ; B = ISENSE_PVCCIN_CPU1_PH1_IMON
C8C12  CAP_A  0.1UF 16V 10% X7R  pkg 0402V  page 188 : A = KR_P1_OCP_RX_DP ; B = KR_P1_OCP_RX_C_DP

(kicad_pcb
	(version 20260206)
	(generator "pcbnew")
	(generator_version "10.0")
	(general
		(thickness 1.6)
		(legacy_teardrops no)
	)
	(paper "A4")
	(title_block
		(title "Wiwynn_Tioga_Pass_MB.brd")
		(comment 1 "Tioga Pass / footprints 1019-1021 of 4770")
	)
	(layers
		(0 "F.Cu" signal "TOP")
		(4 "In1.Cu" signal "L2GND")
		(6 "In2.Cu" signal "L3")
		(8 "In3.Cu" signal "L4GND")
		(10 "In4.Cu" signal "L5")
		(12 "In5.Cu" signal "L6GND")
		(14 "In6.Cu" signal "L7VCC")
		(16 "In7.Cu" signal "L8VCC")
		(18 "In8.Cu" signal "L9GND")
		(20 "In9.Cu" signal "L10")
		(22 "In10.Cu" signal "L11GND")
		(24 "In11.Cu" signal "L12")
		(26 "In12.Cu" signal "L13GND")
		(2 "B.Cu" signal "BOTTOM")
		(9 "F.Adhes" user "F.Adhesive")
		(11 "B.Adhes" user "B.Adhesive")
		(13 "F.Paste" user "Package Geometry/Pastemask Top")
		(15 "B.Paste" user "Package Geometry/Pastemask Bottom")
		(5 "F.SilkS" user "Ref Des/Silkscreen Top")
		(7 "B.SilkS" user "Ref Des/Silkscreen Bottom")
		(1 "F.Mask" user "Board Geometry/Soldermask Top")
		(3 "B.Mask" user "Board Geometry/Soldermask Bottom")
		(17 "Dwgs.User" user "User.Drawings")
		(19 "Cmts.User" user "User.Comments")
		(21 "Eco1.User" user "User.Eco1")
		(23 "Eco2.User" user "User.Eco2")
		(25 "Edge.Cuts" user "Board Geometry/Outline")
		(27 "Margin" user)
		(31 "F.CrtYd" user "Package Geometry/Place Bound Top")
		(29 "B.CrtYd" user "Package Geometry/Place Bound Bottom")
		(35 "F.Fab" user "Ref Des/Assembly Top")
		(33 "B.Fab" user "Ref Des/Assembly Bottom")
	)
	(footprint ""
		(layer "F.Cu")
		(at 23.29434 -86.1568 180)
		(property "Reference" "RF7"
			(at -0.8382 -0.67818 180)
			(unlocked yes)
			(layer "F.SilkS")
			(effects
				(font
					(size 0.4064 0.254)
					(thickness 0.1524)
				)
				(justify left)
			)
		)
		(property "Value" ""
			(at 0 0 180)
			(layer "F.Fab")
			(effects
				(font
					(size 1.27 1.27)
				)
			)
		)
		(duplicate_pad_numbers_are_jumpers no)
		(fp_poly
			(pts
				(xy -0.2794 -0.1016) (xy 0.2794 -0.1016) (xy 0.2794 0.9906) (xy -0.2794 0.9906)
			)
			(stroke
				(width 0)
				(type default)
			)
			(fill no)
			(layer "F.CrtYd")
		)
		(fp_line
			(start 0.2794 0.9906)
			(end 0.2794 -0.1016)
			(stroke
				(width 0.1)
				(type default)
			)
			(layer "F.Fab")
		)
		(fp_line
			(start 0.2794 -0.1016)
			(end -0.2794 -0.1016)
			(stroke
				(width 0.1)
				(type default)
			)
			(layer "F.Fab")
		)
		(fp_line
			(start -0.2794 0.9906)
			(end 0.2794 0.9906)
			(stroke
				(width 0.1)
				(type default)
			)
			(layer "F.Fab")
		)
		(fp_line
			(start -0.2794 -0.1016)
			(end -0.2794 0.9906)
			(stroke
				(width 0.1)
				(type default)
			)
			(layer "F.Fab")
		)
		(pad "1" smd rect
			(at 0 0 180)
			(size 0.508 0.508)
			(layers "F.Cu" "F.Mask" "F.Paste")
			(net "VR_PVCCIN_CPU1_AIREF1")
		)
		(pad "2" smd rect
			(at 0 0.889 180)
			(size 0.508 0.508)
			(layers "F.Cu" "F.Mask" "F.Paste")
			(net "ISENSE_PVCCIN_CPU1_PH1_IMON")
		)
		(zone
			(layer "F.Cu")
			(hatch none 0.5)
			(connect_pads
				(clearance 0)
			)
			(min_thickness 0.25)
			(keepout
				(tracks not_allowed)
				(vias allowed)
				(pads allowed)
				(copperpour not_allowed)
				(footprints allowed)
			)
			(placement
				(enabled no)
				(sheetname "")
			)
			(fill
				(thermal_gap 0.5)
				(thermal_bridge_width 0.5)
				(island_removal_mode 0)
			)
			(polygon
				(pts
					(xy 23.54834 -86.7918) (xy 23.04034 -86.7918) (xy 23.04034 -86.4108) (xy 23.54834 -86.4108)
				)
			)
		)
		(zone
			(layer "F.Cu")
			(hatch none 0.5)
			(connect_pads
				(clearance 0)
			)
			(min_thickness 0.25)
			(keepout
				(tracks allowed)
				(vias not_allowed)
				(pads allowed)
				(copperpour not_allowed)
				(footprints allowed)
			)
			(placement
				(enabled no)
				(sheetname "")
			)
			(fill
				(thermal_gap 0.5)
				(thermal_bridge_width 0.5)
				(island_removal_mode 0)
			)
			(polygon
				(pts
					(xy 23.54834 -86.4108) (xy 23.04034 -86.4108) (xy 23.04034 -86.7918) (xy 23.54834 -86.7918)
				)
			)
		)
	)
	(footprint ""
		(layer "F.Cu")
		(at 407.753566 -96.500442 -90)
		(property "Reference" "C8C12"
			(at -0.8382 -0.67818 270)
			(unlocked yes)
			(layer "F.SilkS")
			(effects
				(font
					(size 0.4064 0.254)
					(thickness 0.1524)
				)
				(justify left)
			)
		)
		(property "Value" ""
			(at 0 0 270)
			(layer "F.Fab")
			(effects
				(font
					(size 1.27 1.27)
				)
			)
		)
		(duplicate_pad_numbers_are_jumpers no)
		(fp_poly
			(pts
				(xy 0.3048 -0.1016) (xy 0.3048 0.9906) (xy -0.3048 0.9906) (xy -0.3048 -0.1016)
			)
			(stroke
				(width 0)
				(type default)
			)
			(fill no)
			(layer "F.CrtYd")
		)
		(fp_line
			(start -0.3048 0.9906)
			(end 0.3048 0.9906)
			(stroke
				(width 0.1)
				(type default)
			)
			(layer "F.Fab")
		)
		(fp_line
			(start 0.3048 0.9906)
			(end 0.3048 -0.1016)
			(stroke
				(width 0.1)
				(type default)
			)
			(layer "F.Fab")
		)
		(fp_line
			(start -0.3048 -0.1016)
			(end -0.3048 0.9906)
			(stroke
				(width 0.1)
				(type default)
			)
			(layer "F.Fab")
		)
		(fp_line
			(start 0.3048 -0.1016)
			(end -0.3048 -0.1016)
			(stroke
				(width 0.1)
				(type default)
			)
			(layer "F.Fab")
		)
		(pad "1" smd rect
			(at 0 0 270)
			(size 0.508 0.508)
			(layers "F.Cu" "F.Mask" "F.Paste")
			(net "KR_P1_OCP_RX_DP")
		)
		(pad "2" smd rect
			(at 0 0.889 270)
			(size 0.508 0.508)
			(layers "F.Cu" "F.Mask" "F.Paste")
			(net "KR_P1_OCP_RX_C_DP")
		)
		(zone
			(layer "F.Cu")
			(hatch none 0.5)
			(connect_pads
				(clearance 0)
			)
			(min_thickness 0.25)
			(keepout
				(tracks not_allowed)
				(vias allowed)
				(pads allowed)
				(copperpour not_allowed)
				(footprints allowed)
			)
			(placement
				(enabled no)
				(sheetname "")
			)
			(fill
				(thermal_gap 0.5)
				(thermal_bridge_width 0.5)
				(island_removal_mode 0)
			)
			(polygon
				(pts
					(xy 407.118566 -96.754442) (xy 407.118566 -96.246442) (xy 407.499566 -96.246442) (xy 407.499566 -96.754442)
				)
			)
		)
		(zone
			(layer "F.Cu")
			(hatch none 0.5)
			(connect_pads
				(clearance 0)
			)
			(min_thickness 0.25)
			(keepout
				(tracks allowed)
				(vias not_allowed)
				(pads allowed)
				(copperpour not_allowed)
				(footprints allowed)
			)
			(placement
				(enabled no)
				(sheetname "")
			)
			(fill
				(thermal_gap 0.5)
				(thermal_bridge_width 0.5)
				(island_removal_mode 0)
			)
			(polygon
				(pts
					(xy 407.499566 -96.754442) (xy 407.499566 -96.246442) (xy 407.118566 -96.246442) (xy 407.118566 -96.754442)
				)
			)
		)
	)
	(footprint ""
		(layer "F.Cu")
		(at 13.8938 -35.687 90)
		(property "Reference" "C1F3"
			(at 0 0 90)
			(layer "F.SilkS")
			(hide yes)
			(effects
				(font
					(size 1.27 1.27)
				)
			)
		)
		(property "Value" ""
			(at 0 0 90)
			(layer "F.Fab")
			(effects
				(font
					(size 1.27 1.27)
				)
			)
		)
		(duplicate_pad_numbers_are_jumpers no)
		(fp_rect
			(start -0.3048 -0.1016)
			(end 0.3048 0.9906)
			(stroke
				(width 0)
				(type default)
			)
			(fill no)
			(layer "F.CrtYd")
		)
		(fp_line
			(start 0.3048 -0.1016)
			(end -0.3048 -0.1016)
			(stroke
				(width 0.1)
				(type default)
			)
			(layer "F.Fab")
		)
		(fp_line
			(start -0.3048 -0.1016)
			(end -0.3048 0.9906)
			(stroke
				(width 0.1)
				(type default)
			)
			(layer "F.Fab")
		)
		(fp_line
			(start 0.3048 0.9906)
			(end 0.3048 -0.1016)
			(stroke
				(width 0.1)
				(type default)
			)
			(layer "F.Fab")
		)
		(fp_line
			(start -0.3048 0.9906)
			(end 0.3048 0.9906)
			(stroke
				(width 0.1)
				(type default)
			)
			(layer "F.Fab")
		)
		(pad "1" smd rect
			(at 0 0 90)
			(size 0.508 0.508)
			(layers "F.Cu" "F.Mask" "F.Paste")
			(net "P3E_CPU1_PE3_MP_C_TXN<7>")
		)
		(pad "2" smd rect
			(at 0 0.889 90)
			(size 0.508 0.508)
			(layers "F.Cu" "F.Mask" "F.Paste")
			(net "P3E_CPU1_PE3_MP_TXN<7>")
		)
		(zone
			(layer "F.Cu")
			(hatch none 0.5)
			(connect_pads
				(clearance 0)
			)
			(min_thickness 0.25)
			(keepout
				(tracks not_allowed)
				(vias allowed)
				(pads allowed)
				(copperpour not_allowed)
				(footprints allowed)
			)
			(placement
				(enabled no)
				(sheetname "")
			)
			(fill
				(thermal_gap 0.5)
				(thermal_bridge_width 0.5)
				(island_removal_mode 0)
			)
			(polygon
				(pts
					(xy 14.1478 -35.433) (xy 14.5288 -35.433) (xy 14.5288 -35.941) (xy 14.1478 -35.941)
				)
			)
		)
		(zone
			(layer "F.Cu")
			(hatch none 0.5)
			(connect_pads
				(clearance 0)
			)
			(min_thickness 0.25)
			(keepout
				(tracks allowed)
				(vias not_allowed)
				(pads allowed)
				(copperpour not_allowed)
				(footprints allowed)
			)
			(placement
				(enabled no)
				(sheetname "")
			)
			(fill
				(thermal_gap 0.5)
				(thermal_bridge_width 0.5)
				(island_removal_mode 0)
			)
			(polygon
				(pts
					(xy 14.1478 -35.433) (xy 14.5288 -35.433) (xy 14.5288 -35.941) (xy 14.1478 -35.941)
				)
			)
		)
	)
)
